# S9S_MB_2U (Grand Teton) — schematic netlist excerpt (pin names and nets, part order shuffled) for the footprints in the layout excerpt that follows; sources: Cadence DE-HDL packaged netlist, KiCad conversion of 03242023_DA0F0TMBIJ0_F0T_Motherboard_J_brd_V01_OCP.brd

R4118  Q_RES  10 1% CHIP  pkg 0402LF  page 202 : A = IRQ_LPC_SERIRQ_ESPI_CS1_N ; B = IRQ_LPC_SERIRQ_ESPI_CS1_R_N
H77  HOLE  EMPTY  pkg TH  page 311 : \1\ = GND
C1647  Q_CAP  0.1UF 25V 10% X7R  pkg 0402  page 202 : A = P3V3_AUX ; B = GND

(kicad_pcb
	(version 20260206)
	(generator "pcbnew")
	(generator_version "10.0")
	(general
		(thickness 1.6)
		(legacy_teardrops no)
	)
	(paper "A4")
	(title_block
		(title "03242023_DA0F0TMBIJ0_F0T_Motherboard_J_brd_V01_OCP.brd")
		(comment 1 "Grand Teton / footprints 398-400 of 6105")
	)
	(layers
		(0 "F.Cu" signal "TOP")
		(4 "In1.Cu" signal "GND")
		(6 "In2.Cu" signal "IN1")
		(8 "In3.Cu" signal "GND1")
		(10 "In4.Cu" signal "IN2")
		(12 "In5.Cu" signal "GND2")
		(14 "In6.Cu" signal "IN3")
		(16 "In7.Cu" signal "GND3")
		(18 "In8.Cu" signal "VCC")
		(20 "In9.Cu" signal "VCC1")
		(22 "In10.Cu" signal "GND4")
		(24 "In11.Cu" signal "IN4")
		(26 "In12.Cu" signal "GND5")
		(28 "In13.Cu" signal "IN5")
		(30 "In14.Cu" signal "GND6")
		(32 "In15.Cu" signal "IN6")
		(34 "In16.Cu" signal "GND7")
		(2 "B.Cu" signal "BOTTOM")
		(9 "F.Adhes" user "F.Adhesive")
		(11 "B.Adhes" user "B.Adhesive")
		(13 "F.Paste" user "Package Geometry/Pastemask Top")
		(15 "B.Paste" user "Package Geometry/Pastemask Bottom")
		(5 "F.SilkS" user "Ref Des/Silkscreen Top")
		(7 "B.SilkS" user "Ref Des/Silkscreen Bottom")
		(1 "F.Mask" user "Board Geometry/Soldermask Top")
		(3 "B.Mask" user "Board Geometry/Soldermask Bottom")
		(17 "Dwgs.User" user "User.Drawings")
		(19 "Cmts.User" user "User.Comments")
		(21 "Eco1.User" user "User.Eco1")
		(23 "Eco2.User" user "User.Eco2")
		(25 "Edge.Cuts" user "Board Geometry/Outline")
		(27 "Margin" user)
		(31 "F.CrtYd" user "Package Geometry/Place Bound Top")
		(29 "B.CrtYd" user "Package Geometry/Place Bound Bottom")
		(35 "F.Fab" user "Ref Des/Assembly Top")
		(33 "B.Fab" user "Ref Des/Assembly Bottom")
	)
	(footprint ""
		(layer "F.Cu")
		(at 333.23784 -13.718032 -90)
		(property "Reference" "C1647"
			(at 0 0 270)
			(layer "F.SilkS")
			(hide yes)
			(effects
				(font
					(size 1.27 1.27)
				)
			)
		)
		(property "Value" ""
			(at 0 0 270)
			(layer "F.Fab")
			(effects
				(font
					(size 1.27 1.27)
				)
			)
		)
		(duplicate_pad_numbers_are_jumpers no)
		(fp_line
			(start -0.7874 0.4064)
			(end -0.7874 -0.4064)
			(stroke
				(width 0.1524)
				(type default)
			)
			(layer "F.SilkS")
		)
		(fp_line
			(start 0.7874 0.4064)
			(end -0.7874 0.4064)
			(stroke
				(width 0.1524)
				(type default)
			)
			(layer "F.SilkS")
		)
		(fp_line
			(start -0.7874 -0.4064)
			(end 0.7874 -0.4064)
			(stroke
				(width 0.1524)
				(type default)
			)
			(layer "F.SilkS")
		)
		(fp_line
			(start 0.7874 -0.4064)
			(end 0.7874 0.4064)
			(stroke
				(width 0.1524)
				(type default)
			)
			(layer "F.SilkS")
		)
		(fp_line
			(start -0.67945 0.3048)
			(end -0.67945 -0.305054)
			(stroke
				(width 0.1)
				(type default)
			)
			(layer "F.Fab")
		)
		(fp_line
			(start -0.12065 0.3048)
			(end -0.67945 0.3048)
			(stroke
				(width 0.1)
				(type default)
			)
			(layer "F.Fab")
		)
		(fp_line
			(start 0.120396 0.3048)
			(end 0.120396 0.2794)
			(stroke
				(width 0.1)
				(type default)
			)
			(layer "F.Fab")
		)
		(fp_line
			(start 0.67945 0.3048)
			(end 0.120396 0.3048)
			(stroke
				(width 0.1)
				(type default)
			)
			(layer "F.Fab")
		)
		(fp_line
			(start -0.12065 0.2794)
			(end -0.12065 0.3048)
			(stroke
				(width 0.1)
				(type default)
			)
			(layer "F.Fab")
		)
		(fp_line
			(start 0.120396 0.2794)
			(end -0.12065 0.2794)
			(stroke
				(width 0.1)
				(type default)
			)
			(layer "F.Fab")
		)
		(fp_line
			(start -0.12065 -0.2794)
			(end 0.12065 -0.2794)
			(stroke
				(width 0.1)
				(type default)
			)
			(layer "F.Fab")
		)
		(fp_line
			(start 0.12065 -0.2794)
			(end 0.12065 -0.3048)
			(stroke
				(width 0.1)
				(type default)
			)
			(layer "F.Fab")
		)
		(fp_line
			(start 0.12065 -0.3048)
			(end 0.67945 -0.3048)
			(stroke
				(width 0.1)
				(type default)
			)
			(layer "F.Fab")
		)
		(fp_line
			(start 0.67945 -0.3048)
			(end 0.67945 0.3048)
			(stroke
				(width 0.1)
				(type default)
			)
			(layer "F.Fab")
		)
		(fp_line
			(start -0.67945 -0.305054)
			(end -0.12065 -0.305054)
			(stroke
				(width 0.1)
				(type default)
			)
			(layer "F.Fab")
		)
		(fp_line
			(start -0.12065 -0.305054)
			(end -0.12065 -0.2794)
			(stroke
				(width 0.1)
				(type default)
			)
			(layer "F.Fab")
		)
		(pad "1" smd circle
			(at -0.40005 0 270)
			(size 0 0)
			(layers "F.Cu" "F.Mask" "F.Paste")
			(net "P3V3_AUX")
		)
		(pad "2" smd circle
			(at 0.40005 0 270)
			(size 0 0)
			(layers "F.Cu" "F.Mask" "F.Paste")
			(net "GND")
		)
	)
	(footprint ""
		(layer "F.Cu")
		(at 331.917802 -20.77085)
		(property "Reference" "R4118"
			(at 0 0 0)
			(layer "F.SilkS")
			(hide yes)
			(effects
				(font
					(size 1.27 1.27)
				)
			)
		)
		(property "Value" ""
			(at 0 0 0)
			(layer "F.Fab")
			(effects
				(font
					(size 1.27 1.27)
				)
			)
		)
		(duplicate_pad_numbers_are_jumpers no)
		(fp_line
			(start -0.7874 -0.4064)
			(end 0.7874 -0.4064)
			(stroke
				(width 0.1524)
				(type default)
			)
			(layer "F.SilkS")
		)
		(fp_line
			(start -0.7874 0.4064)
			(end -0.7874 -0.4064)
			(stroke
				(width 0.1524)
				(type default)
			)
			(layer "F.SilkS")
		)
		(fp_line
			(start 0.7874 -0.4064)
			(end 0.7874 0.4064)
			(stroke
				(width 0.1524)
				(type default)
			)
			(layer "F.SilkS")
		)
		(fp_line
			(start 0.7874 0.4064)
			(end -0.7874 0.4064)
			(stroke
				(width 0.1524)
				(type default)
			)
			(layer "F.SilkS")
		)
		(fp_line
			(start -0.67945 -0.305054)
			(end -0.12065 -0.305054)
			(stroke
				(width 0.1)
				(type default)
			)
			(layer "F.Fab")
		)
		(fp_line
			(start -0.67945 0.3048)
			(end -0.67945 -0.305054)
			(stroke
				(width 0.1)
				(type default)
			)
			(layer "F.Fab")
		)
		(fp_line
			(start -0.12065 -0.305054)
			(end -0.12065 -0.2794)
			(stroke
				(width 0.1)
				(type default)
			)
			(layer "F.Fab")
		)
		(fp_line
			(start -0.12065 -0.2794)
			(end 0.12065 -0.2794)
			(stroke
				(width 0.1)
				(type default)
			)
			(layer "F.Fab")
		)
		(fp_line
			(start -0.12065 0.2794)
			(end -0.12065 0.3048)
			(stroke
				(width 0.1)
				(type default)
			)
			(layer "F.Fab")
		)
		(fp_line
			(start -0.12065 0.3048)
			(end -0.67945 0.3048)
			(stroke
				(width 0.1)
				(type default)
			)
			(layer "F.Fab")
		)
		(fp_line
			(start 0.120396 0.2794)
			(end -0.12065 0.2794)
			(stroke
				(width 0.1)
				(type default)
			)
			(layer "F.Fab")
		)
		(fp_line
			(start 0.120396 0.3048)
			(end 0.120396 0.2794)
			(stroke
				(width 0.1)
				(type default)
			)
			(layer "F.Fab")
		)
		(fp_line
			(start 0.12065 -0.3048)
			(end 0.67945 -0.3048)
			(stroke
				(width 0.1)
				(type default)
			)
			(layer "F.Fab")
		)
		(fp_line
			(start 0.12065 -0.2794)
			(end 0.12065 -0.3048)
			(stroke
				(width 0.1)
				(type default)
			)
			(layer "F.Fab")
		)
		(fp_line
			(start 0.67945 -0.3048)
			(end 0.67945 0.3048)
			(stroke
				(width 0.1)
				(type default)
			)
			(layer "F.Fab")
		)
		(fp_line
			(start 0.67945 0.3048)
			(end 0.120396 0.3048)
			(stroke
				(width 0.1)
				(type default)
			)
			(layer "F.Fab")
		)
		(pad "1" smd circle
			(at -0.40005 0)
			(size 0 0)
			(layers "F.Cu" "F.Mask" "F.Paste")
			(net "IRQ_LPC_SERIRQ_ESPI_CS1_N")
		)
		(pad "2" smd circle
			(at 0.40005 0)
			(size 0 0)
			(layers "F.Cu" "F.Mask" "F.Paste")
			(net "IRQ_LPC_SERIRQ_ESPI_CS1_R_N")
		)
	)
	(footprint ""
		(layer "F.Cu")
		(at 228.649784 -44.500038)
		(property "Reference" "H77"
			(at -1.143 -3.266948 0)
			(unlocked yes)
			(layer "B.SilkS")
			(effects
				(font
					(size 0.7874 0.5842)
					(thickness 0.1524)
				)
				(justify left mirror)
			)
		)
		(property "Value" ""
			(at 0 0 0)
			(layer "F.Fab")
			(effects
				(font
					(size 1.27 1.27)
				)
			)
		)
		(duplicate_pad_numbers_are_jumpers no)
		(pad "1" thru_hole rect
			(at 0 0)
			(size 4.2164 5.0038)
			(drill 2.0066
				(offset 0.099822 0)
			)
			(layers "*.Cu" "*.Mask")
			(remove_unused_layers no)
			(net "GND")
			(clearance -0.8509)
			(padstack
				(mode front_inner_back)
				(layer "Inner"
					(shape circle)
					(size 4.0132 4.0132)
					(clearance -0.7493)
				)
				(layer "B.Cu"
					(shape circle)
					(size 4.0132 4.0132)
					(clearance -0.7493)
				)
			)
		)
	)
)
